# T6G (Grand Teton) — schematic netlist excerpt (pin names and nets, part order shuffled) for the footprints in the layout excerpt that follows; sources: Cadence DE-HDL packaged netlist, KiCad conversion of 04192023_DAF0TMB3IC0_F0TG_MB_C_brd_V02_OCP.brd

R1347  Q_RES  33.2 1% CHIP  pkg 0402LF  page 251 : A = SMB_INA230_3V3AUX_SDA ; B = SMB_INA230_7_3V3AUX_SDA_R
R1703  Q_RES  4.7K 5% CHIP  pkg 0402LF  page 148 : A = P1V8_AUX ; B = SMB_M2_P1_1V8AUX_SCL_R
R6152  Q_RES  0 5% CHIP  pkg 0201LF  page 113 : A = P2E_MB_BMC_TX_C_DP<0> ; B = P2E_MB_BMC_TX_C_R1_DP<0>

(kicad_pcb
	(version 20260206)
	(generator "pcbnew")
	(generator_version "10.0")
	(general
		(thickness 1.6)
		(legacy_teardrops no)
	)
	(paper "A4")
	(title_block
		(title "04192023_DAF0TMB3IC0_F0TG_MB_C_brd_V02_OCP.brd")
		(comment 1 "Grand Teton / footprints 2135-2137 of 8354")
	)
	(layers
		(0 "F.Cu" signal "TOP")
		(4 "In1.Cu" signal "GND")
		(6 "In2.Cu" signal "IN1")
		(8 "In3.Cu" signal "GND1")
		(10 "In4.Cu" signal "IN2")
		(12 "In5.Cu" signal "GND2")
		(14 "In6.Cu" signal "IN3")
		(16 "In7.Cu" signal "GND3")
		(18 "In8.Cu" signal "VCC")
		(20 "In9.Cu" signal "VCC1")
		(22 "In10.Cu" signal "GND4")
		(24 "In11.Cu" signal "IN4")
		(26 "In12.Cu" signal "GND5")
		(28 "In13.Cu" signal "IN5")
		(30 "In14.Cu" signal "GND6")
		(32 "In15.Cu" signal "IN6")
		(34 "In16.Cu" signal "GND7")
		(2 "B.Cu" signal "BOTTOM")
		(9 "F.Adhes" user "F.Adhesive")
		(11 "B.Adhes" user "B.Adhesive")
		(13 "F.Paste" user "Package Geometry/Pastemask Top")
		(15 "B.Paste" user "Package Geometry/Pastemask Bottom")
		(5 "F.SilkS" user "Ref Des/Silkscreen Top")
		(7 "B.SilkS" user "Ref Des/Silkscreen Bottom")
		(1 "F.Mask" user "Board Geometry/Soldermask Top")
		(3 "B.Mask" user "Board Geometry/Soldermask Bottom")
		(17 "Dwgs.User" user "User.Drawings")
		(19 "Cmts.User" user "User.Comments")
		(21 "Eco1.User" user "User.Eco1")
		(23 "Eco2.User" user "User.Eco2")
		(25 "Edge.Cuts" user "Board Geometry/Outline")
		(27 "Margin" user)
		(31 "F.CrtYd" user "Package Geometry/Place Bound Top")
		(29 "B.CrtYd" user "Package Geometry/Place Bound Bottom")
		(35 "F.Fab" user "Ref Des/Assembly Top")
		(33 "B.Fab" user "Ref Des/Assembly Bottom")
	)
	(footprint ""
		(layer "F.Cu")
		(at 148.641562 -43.03141)
		(property "Reference" "R1703"
			(at 0 0 0)
			(layer "F.SilkS")
			(hide yes)
			(effects
				(font
					(size 1.27 1.27)
				)
			)
		)
		(property "Value" ""
			(at 0 0 0)
			(layer "F.Fab")
			(effects
				(font
					(size 1.27 1.27)
				)
			)
		)
		(duplicate_pad_numbers_are_jumpers no)
		(fp_line
			(start -0.7874 -0.4064)
			(end 0.7874 -0.4064)
			(stroke
				(width 0.1524)
				(type default)
			)
			(layer "F.SilkS")
		)
		(fp_line
			(start -0.7874 0.4064)
			(end -0.7874 -0.4064)
			(stroke
				(width 0.1524)
				(type default)
			)
			(layer "F.SilkS")
		)
		(fp_line
			(start 0.7874 -0.4064)
			(end 0.7874 0.4064)
			(stroke
				(width 0.1524)
				(type default)
			)
			(layer "F.SilkS")
		)
		(fp_line
			(start 0.7874 0.4064)
			(end -0.7874 0.4064)
			(stroke
				(width 0.1524)
				(type default)
			)
			(layer "F.SilkS")
		)
		(fp_line
			(start -0.67945 -0.305054)
			(end -0.12065 -0.305054)
			(stroke
				(width 0.1)
				(type default)
			)
			(layer "F.Fab")
		)
		(fp_line
			(start -0.67945 0.3048)
			(end -0.67945 -0.305054)
			(stroke
				(width 0.1)
				(type default)
			)
			(layer "F.Fab")
		)
		(fp_line
			(start -0.12065 -0.305054)
			(end -0.12065 -0.2794)
			(stroke
				(width 0.1)
				(type default)
			)
			(layer "F.Fab")
		)
		(fp_line
			(start -0.12065 -0.2794)
			(end 0.12065 -0.2794)
			(stroke
				(width 0.1)
				(type default)
			)
			(layer "F.Fab")
		)
		(fp_line
			(start -0.12065 0.2794)
			(end -0.12065 0.3048)
			(stroke
				(width 0.1)
				(type default)
			)
			(layer "F.Fab")
		)
		(fp_line
			(start -0.12065 0.3048)
			(end -0.67945 0.3048)
			(stroke
				(width 0.1)
				(type default)
			)
			(layer "F.Fab")
		)
		(fp_line
			(start 0.120396 0.2794)
			(end -0.12065 0.2794)
			(stroke
				(width 0.1)
				(type default)
			)
			(layer "F.Fab")
		)
		(fp_line
			(start 0.120396 0.3048)
			(end 0.120396 0.2794)
			(stroke
				(width 0.1)
				(type default)
			)
			(layer "F.Fab")
		)
		(fp_line
			(start 0.12065 -0.3048)
			(end 0.67945 -0.3048)
			(stroke
				(width 0.1)
				(type default)
			)
			(layer "F.Fab")
		)
		(fp_line
			(start 0.12065 -0.2794)
			(end 0.12065 -0.3048)
			(stroke
				(width 0.1)
				(type default)
			)
			(layer "F.Fab")
		)
		(fp_line
			(start 0.67945 -0.3048)
			(end 0.67945 0.3048)
			(stroke
				(width 0.1)
				(type default)
			)
			(layer "F.Fab")
		)
		(fp_line
			(start 0.67945 0.3048)
			(end 0.120396 0.3048)
			(stroke
				(width 0.1)
				(type default)
			)
			(layer "F.Fab")
		)
		(pad "1" smd circle
			(at -0.40005 0)
			(size 0 0)
			(layers "F.Cu" "F.Mask" "F.Paste")
			(net "P1V8_AUX")
		)
		(pad "2" smd circle
			(at 0.40005 0)
			(size 0 0)
			(layers "F.Cu" "F.Mask" "F.Paste")
			(net "SMB_M2_P1_1V8AUX_SCL_R")
		)
	)
	(footprint ""
		(layer "F.Cu")
		(at 146.571208 -50.160174)
		(property "Reference" "R1347"
			(at 0 0 0)
			(layer "F.SilkS")
			(hide yes)
			(effects
				(font
					(size 1.27 1.27)
				)
			)
		)
		(property "Value" ""
			(at 0 0 0)
			(layer "F.Fab")
			(effects
				(font
					(size 1.27 1.27)
				)
			)
		)
		(duplicate_pad_numbers_are_jumpers no)
		(fp_line
			(start -0.7874 -0.4064)
			(end 0.7874 -0.4064)
			(stroke
				(width 0.1524)
				(type default)
			)
			(layer "F.SilkS")
		)
		(fp_line
			(start -0.7874 0.4064)
			(end -0.7874 -0.4064)
			(stroke
				(width 0.1524)
				(type default)
			)
			(layer "F.SilkS")
		)
		(fp_line
			(start 0.7874 -0.4064)
			(end 0.7874 0.4064)
			(stroke
				(width 0.1524)
				(type default)
			)
			(layer "F.SilkS")
		)
		(fp_line
			(start 0.7874 0.4064)
			(end -0.7874 0.4064)
			(stroke
				(width 0.1524)
				(type default)
			)
			(layer "F.SilkS")
		)
		(fp_line
			(start -0.67945 -0.305054)
			(end -0.12065 -0.305054)
			(stroke
				(width 0.1)
				(type default)
			)
			(layer "F.Fab")
		)
		(fp_line
			(start -0.67945 0.3048)
			(end -0.67945 -0.305054)
			(stroke
				(width 0.1)
				(type default)
			)
			(layer "F.Fab")
		)
		(fp_line
			(start -0.12065 -0.305054)
			(end -0.12065 -0.2794)
			(stroke
				(width 0.1)
				(type default)
			)
			(layer "F.Fab")
		)
		(fp_line
			(start -0.12065 -0.2794)
			(end 0.12065 -0.2794)
			(stroke
				(width 0.1)
				(type default)
			)
			(layer "F.Fab")
		)
		(fp_line
			(start -0.12065 0.2794)
			(end -0.12065 0.3048)
			(stroke
				(width 0.1)
				(type default)
			)
			(layer "F.Fab")
		)
		(fp_line
			(start -0.12065 0.3048)
			(end -0.67945 0.3048)
			(stroke
				(width 0.1)
				(type default)
			)
			(layer "F.Fab")
		)
		(fp_line
			(start 0.120396 0.2794)
			(end -0.12065 0.2794)
			(stroke
				(width 0.1)
				(type default)
			)
			(layer "F.Fab")
		)
		(fp_line
			(start 0.120396 0.3048)
			(end 0.120396 0.2794)
			(stroke
				(width 0.1)
				(type default)
			)
			(layer "F.Fab")
		)
		(fp_line
			(start 0.12065 -0.3048)
			(end 0.67945 -0.3048)
			(stroke
				(width 0.1)
				(type default)
			)
			(layer "F.Fab")
		)
		(fp_line
			(start 0.12065 -0.2794)
			(end 0.12065 -0.3048)
			(stroke
				(width 0.1)
				(type default)
			)
			(layer "F.Fab")
		)
		(fp_line
			(start 0.67945 -0.3048)
			(end 0.67945 0.3048)
			(stroke
				(width 0.1)
				(type default)
			)
			(layer "F.Fab")
		)
		(fp_line
			(start 0.67945 0.3048)
			(end 0.120396 0.3048)
			(stroke
				(width 0.1)
				(type default)
			)
			(layer "F.Fab")
		)
		(pad "1" smd circle
			(at -0.40005 0)
			(size 0 0)
			(layers "F.Cu" "F.Mask" "F.Paste")
			(net "SMB_INA230_3V3AUX_SDA")
		)
		(pad "2" smd circle
			(at 0.40005 0)
			(size 0 0)
			(layers "F.Cu" "F.Mask" "F.Paste")
			(net "SMB_INA230_7_3V3AUX_SDA_R")
		)
	)
	(footprint ""
		(layer "F.Cu")
		(at 39.309294 -422.06037 180)
		(property "Reference" "R6152"
			(at 0 0 180)
			(layer "F.SilkS")
			(hide yes)
			(effects
				(font
					(size 1.27 1.27)
				)
			)
		)
		(property "Value" ""
			(at 0 0 180)
			(layer "F.Fab")
			(effects
				(font
					(size 1.27 1.27)
				)
			)
		)
		(duplicate_pad_numbers_are_jumpers no)
		(fp_line
			(start 0.32512 0.175006)
			(end -0.32512 0.175006)
			(stroke
				(width 0.1)
				(type default)
			)
			(layer "F.Fab")
		)
		(fp_line
			(start 0.32512 -0.175006)
			(end 0.32512 0.175006)
			(stroke
				(width 0.1)
				(type default)
			)
			(layer "F.Fab")
		)
		(fp_line
			(start -0.32512 0.175006)
			(end -0.32512 -0.175006)
			(stroke
				(width 0.1)
				(type default)
			)
			(layer "F.Fab")
		)
		(fp_line
			(start -0.32512 -0.175006)
			(end 0.32512 -0.175006)
			(stroke
				(width 0.1)
				(type default)
			)
			(layer "F.Fab")
		)
		(pad "1" smd rect
			(at -0.2667 0 180)
			(size 0.3048 0.381)
			(layers "F.Cu" "F.Mask" "F.Paste")
			(net "P2E_MB_BMC_TX_C_DP<0>")
		)
		(pad "2" smd rect
			(at 0.2667 0)
			(size 0.3048 0.381)
			(layers "F.Cu" "F.Mask" "F.Paste")
			(net "P2E_MB_BMC_TX_C_R1_DP<0>")
		)
	)
)
